#ISCELL
  mstr_misc dns *
  *
#ISCELL
  pure_quanta quanta_title_block_c *
  *
#CELL
  pure_quanta q_inductor4p_14 *
  page195_i100
#ISCELL
  pure_quanta_power vcc_core *
  page195_i101
#CELL
  pure_quanta q_cap *
  page195_i102
#CELL
  pure_quanta q_cap *
  page195_i103
#ISCELL
  pure_quanta_power universal_gnd *
  page195_i104
#CELL
  pure_quanta q_cap *
  page195_i106
#CELL
  pure_quanta q_cap *
  page195_i107
#CELL
  pure_quanta q_cap *
  page195_i108
#CELL
  pure_quanta q_cap *
  page195_i109
#CELL
  pure_quanta q_res *
  page195_i110
#CELL
  pure_quanta q_res *
  page195_i111
#CELL
  pure_quanta q_cap *
  page195_i112
#ISCELL
  pure_quanta_power universal_gnd *
  page195_i113
#CELL
  pure_quanta q_res *
  page195_i115
#CELL
  pure_quanta q_cap *
  page195_i116
#ISCELL
  pure_quanta_power universal_gnd *
  page195_i117
#ISCELL
  standard offpage *
  page195_i118
#ISCELL
  standard offpage *
  page195_i119
#ISCELL
  pure_quanta_power universal_gnd *
  page195_i120
#ISCELL
  standard offpage *
  page195_i121
#ISCELL
  standard offpage *
  page195_i122
#CELL
  pure_quanta q_res *
  page195_i123
#ISCELL
  pure_quanta_power universal_gnd *
  page195_i124
#CELL
  pure_quanta q_cap *
  page195_i125
#ISCELL
  pure_quanta_power universal_gnd *
  page195_i126
#ISCELL
  pure_quanta_power universal_gnd *
  page195_i127
#CELL
  pure_quanta q_res *
  page195_i128
#CELL
  pure_quanta q_cap *
  page195_i129
#ISCELL
  pure_quanta_power universal_gnd *
  page195_i130
#CELL
  pure_quanta q_res *
  page195_i131
#CELL
  pure_quanta q_cap *
  page195_i132
#ISCELL
  pure_quanta_power vcc_core *
  page195_i133
#ISCELL
  pure_quanta_power vcc_core *
  page195_i134
#ISCELL
  pure_quanta_power universal_gnd *
  page195_i135
#CELL
  pure_quanta q_inductor *
  page195_i136
#ISCELL
  pure_quanta_power universal_gnd *
  page195_i20
#CELL
  pure_quanta q_res *
  page195_i21
#ISCELL
  standard offpage *
  page195_i23
#ISCELL
  standard offpage *
  page195_i25
#ISCELL
  standard offpage *
  page195_i26
#ISCELL
  standard offpage *
  page195_i28
#CELL
  pure_quanta isl99390frztr5935 *
  page195_i31
#ISCELL
  pure_quanta_power universal_gnd *
  page195_i36
#CELL
  pure_quanta q_cap *
  page195_i39
#CELL
  pure_quanta q_cap *
  page195_i40
#ISCELL
  pure_quanta_power universal_gnd *
  page195_i54
#CELL
  pure_quanta q_cap *
  page195_i59
#CELL
  pure_quanta q_cap *
  page195_i60
#ISCELL
  pure_quanta_power vcc_core *
  page195_i61
#ISCELL
  standard offpage *
  page195_i73
#ISCELL
  standard offpage *
  page195_i75
#CELL
  pure_quanta q_res *
  page195_i76
#ISCELL
  pure_quanta_power vcc_core *
  page195_i77
#ISCELL
  pure_quanta_power universal_gnd *
  page195_i78
#CELL
  pure_quanta q_cap *
  page195_i79
#CELL
  pure_quanta q_cap *
  page195_i80
#CELL
  pure_quanta q_inductor4p_14 *
  page195_i82
#CELL
  pure_quanta q_cap *
  page195_i83
#CELL
  pure_quanta q_cap *
  page195_i84
#CELL
  pure_quanta q_res *
  page195_i85
#CELL
  pure_quanta q_cap *
  page195_i86
#CELL
  pure_quanta q_cap *
  page195_i87
#ISCELL
  pure_quanta_power universal_gnd *
  page195_i88
#ISCELL
  pure_quanta_power universal_gnd *
  page195_i89
#CELL
  pure_quanta q_res *
  page195_i90
#CELL
  pure_quanta q_cap *
  page195_i91
#ISCELL
  pure_quanta_power universal_gnd *
  page195_i93
#CELL
  pure_quanta isl99390frztr5935 *
  page195_i94
#ISCELL
  pure_quanta_power vcc_core *
  page195_i95
#CELL
  pure_quanta q_cap *
  page195_i96
#CELL
  pure_quanta q_cap *
  page195_i97
#ISCELL
  pure_quanta_power universal_gnd *
  page195_i98
#ISCELL
  standard offpage *
  page195_i99
